(kicad_pcb
	(version 20260206)
	(generator "pcbnew")
	(generator_version "10.0")
	(general
		(thickness 1.6)
		(legacy_teardrops no)
	)
	(paper "A4")
	(title_block
		(title "peb — Lightning_PEB_BRD.brd")
		(comment 1 "Lightning (Wiwynn / Facebook NVMe JBOF) / footprints 2022-2029 of 2563")
	)
	(layers
		(0 "F.Cu" signal "TOP")
		(4 "In1.Cu" signal "L2GND")
		(6 "In2.Cu" signal "L3")
		(8 "In3.Cu" signal "L4VCC")
		(10 "In4.Cu" signal "L5VCC")
		(12 "In5.Cu" signal "L6")
		(14 "In6.Cu" signal "L7GND")
		(2 "B.Cu" signal "BOTTOM")
		(9 "F.Adhes" user "F.Adhesive")
		(11 "B.Adhes" user "B.Adhesive")
		(13 "F.Paste" user "Package Geometry/Pastemask Top")
		(15 "B.Paste" user "Package Geometry/Pastemask Bottom")
		(5 "F.SilkS" user "Ref Des/Silkscreen Top")
		(7 "B.SilkS" user "Ref Des/Silkscreen Bottom")
		(1 "F.Mask" user "Board Geometry/Soldermask Top")
		(3 "B.Mask" user "Board Geometry/Soldermask Bottom")
		(17 "Dwgs.User" user "User.Drawings")
		(19 "Cmts.User" user "User.Comments")
		(21 "Eco1.User" user "User.Eco1")
		(23 "Eco2.User" user "User.Eco2")
		(25 "Edge.Cuts" user "Board Geometry/Outline")
		(27 "Margin" user)
		(31 "F.CrtYd" user "Package Geometry/Place Bound Top")
		(29 "B.CrtYd" user "Package Geometry/Place Bound Bottom")
		(35 "F.Fab" user "Ref Des/Assembly Top")
		(33 "B.Fab" user "Ref Des/Assembly Bottom")
	)
	(footprint ""
		(layer "B.Cu")
		(at 53.4162 -115.7732)
		(property "Reference" "R531"
			(at 0 0 0)
			(layer "B.SilkS")
			(hide yes)
			(effects
				(font
					(size 1.27 1.27)
				)
				(justify mirror)
			)
		)
		(property "Value" "0R2J-2-GP"
			(at -0.064008 -3.993896 0)
			(unlocked yes)
			(layer "B.Fab")
			(hide yes)
			(effects
				(font
					(size 1.016 1.016)
					(thickness 0.1524)
				)
				(justify mirror)
			)
		)
		(property "Device Type" "R402H16"
			(at -0.064008 -5.517896 0)
			(unlocked yes)
			(layer "B.Fab")
			(hide yes)
			(effects
				(font
					(size 1.016 1.016)
					(thickness 0.1524)
				)
				(justify mirror)
			)
		)
		(duplicate_pad_numbers_are_jumpers no)
		(fp_line
			(start -0.508 -0.9398)
			(end 0.508 -0.9398)
			(stroke
				(width 0.1524)
				(type default)
			)
			(layer "B.SilkS")
		)
		(fp_line
			(start 0.508 -0.9398)
			(end 0.508 0.9398)
			(stroke
				(width 0.1524)
				(type default)
			)
			(layer "B.SilkS")
		)
		(fp_rect
			(start 0.508 0.9398)
			(end -0.508 -0.9398)
			(stroke
				(width 0)
				(type default)
			)
			(fill no)
			(layer "B.CrtYd")
		)
		(fp_rect
			(start 0.508 0.9398)
			(end -0.508 -0.9398)
			(stroke
				(width 0)
				(type default)
			)
			(fill no)
			(layer "B.Fab")
		)
		(pad "1" smd custom
			(at 0 -0.4445 180)
			(size 0.1397 0.1397)
			(layers "B.Cu" "B.Mask" "B.Paste")
			(net "BMC0_SCL12_R")
			(options
				(clearance outline)
				(anchor circle)
			)
			(primitives
				(gr_poly
					(pts
						(arc
							(start -0.1778 0.2794)
							(mid -0.249642 0.249642)
							(end -0.2794 0.1778)
						)
						(arc
							(start -0.2794 -0.1778)
							(mid -0.249642 -0.249642)
							(end -0.1778 -0.2794)
						)
						(arc
							(start 0.1778 -0.2794)
							(mid 0.249642 -0.249642)
							(end 0.2794 -0.1778)
						)
						(arc
							(start 0.2794 0.1778)
							(mid 0.249642 0.249642)
							(end 0.1778 0.2794)
						)
					)
					(width 0)
					(fill yes)
				)
			)
		)
		(pad "2" smd custom
			(at 0 0.4445 180)
			(size 0.1397 0.1397)
			(layers "B.Cu" "B.Mask" "B.Paste")
			(net "BMC_I2C12_MINI6_SCL_S")
			(options
				(clearance outline)
				(anchor circle)
			)
			(primitives
				(gr_poly
					(pts
						(arc
							(start -0.1778 0.2794)
							(mid -0.249642 0.249642)
							(end -0.2794 0.1778)
						)
						(arc
							(start -0.2794 -0.1778)
							(mid -0.249642 -0.249642)
							(end -0.1778 -0.2794)
						)
						(arc
							(start 0.1778 -0.2794)
							(mid 0.249642 -0.249642)
							(end 0.2794 -0.1778)
						)
						(arc
							(start 0.2794 0.1778)
							(mid 0.249642 0.249642)
							(end 0.1778 0.2794)
						)
					)
					(width 0)
					(fill yes)
				)
			)
		)
	)
	(footprint ""
		(layer "B.Cu")
		(at 341.6046 -181.8386)
		(property "Reference" "R3243"
			(at 0 0 0)
			(layer "B.SilkS")
			(hide yes)
			(effects
				(font
					(size 1.27 1.27)
				)
				(justify mirror)
			)
		)
		(property "Value" "0R2J-2-GP"
			(at -0.064008 -3.993896 0)
			(unlocked yes)
			(layer "B.Fab")
			(hide yes)
			(effects
				(font
					(size 1.016 1.016)
					(thickness 0.1524)
				)
				(justify mirror)
			)
		)
		(property "Device Type" "R402H16"
			(at -0.064008 -5.517896 0)
			(unlocked yes)
			(layer "B.Fab")
			(hide yes)
			(effects
				(font
					(size 1.016 1.016)
					(thickness 0.1524)
				)
				(justify mirror)
			)
		)
		(duplicate_pad_numbers_are_jumpers no)
		(fp_line
			(start -0.508 -0.9398)
			(end 0.508 -0.9398)
			(stroke
				(width 0.1524)
				(type default)
			)
			(layer "B.SilkS")
		)
		(fp_line
			(start 0.508 -0.9398)
			(end 0.508 0.9398)
			(stroke
				(width 0.1524)
				(type default)
			)
			(layer "B.SilkS")
		)
		(fp_rect
			(start 0.508 0.9398)
			(end -0.508 -0.9398)
			(stroke
				(width 0)
				(type default)
			)
			(fill no)
			(layer "B.CrtYd")
		)
		(fp_rect
			(start 0.508 0.9398)
			(end -0.508 -0.9398)
			(stroke
				(width 0)
				(type default)
			)
			(fill no)
			(layer "B.Fab")
		)
		(pad "1" smd custom
			(at 0 -0.4445 180)
			(size 0.1397 0.1397)
			(layers "B.Cu" "B.Mask" "B.Paste")
			(net "SSD_PERST#14")
			(options
				(clearance outline)
				(anchor circle)
			)
			(primitives
				(gr_poly
					(pts
						(arc
							(start -0.1778 0.2794)
							(mid -0.249642 0.249642)
							(end -0.2794 0.1778)
						)
						(arc
							(start -0.2794 -0.1778)
							(mid -0.249642 -0.249642)
							(end -0.1778 -0.2794)
						)
						(arc
							(start 0.1778 -0.2794)
							(mid 0.249642 -0.249642)
							(end 0.2794 -0.1778)
						)
						(arc
							(start 0.2794 0.1778)
							(mid 0.249642 0.249642)
							(end 0.1778 0.2794)
						)
					)
					(width 0)
					(fill yes)
				)
			)
		)
		(pad "2" smd custom
			(at 0 0.4445 180)
			(size 0.1397 0.1397)
			(layers "B.Cu" "B.Mask" "B.Paste")
			(net "SSD_PERST#0_B14")
			(options
				(clearance outline)
				(anchor circle)
			)
			(primitives
				(gr_poly
					(pts
						(arc
							(start -0.1778 0.2794)
							(mid -0.249642 0.249642)
							(end -0.2794 0.1778)
						)
						(arc
							(start -0.2794 -0.1778)
							(mid -0.249642 -0.249642)
							(end -0.1778 -0.2794)
						)
						(arc
							(start 0.1778 -0.2794)
							(mid 0.249642 -0.249642)
							(end 0.2794 -0.1778)
						)
						(arc
							(start 0.2794 0.1778)
							(mid 0.249642 0.249642)
							(end 0.1778 0.2794)
						)
					)
					(width 0)
					(fill yes)
				)
			)
		)
	)
	(footprint ""
		(layer "B.Cu")
		(at 310.007 -66.929 180)
		(property "Reference" "PG56"
			(at 0 0 0)
			(layer "B.SilkS")
			(hide yes)
			(effects
				(font
					(size 1.27 1.27)
				)
				(justify mirror)
			)
		)
		(property "Value" "GAP-CLOSE-PWR-3-GP"
			(at -0.0254 -6.5786 180)
			(unlocked yes)
			(layer "B.Fab")
			(hide yes)
			(effects
				(font
					(size 1.016 1.016)
					(thickness 0.1524)
				)
				(justify mirror)
			)
		)
		(property "Device Type" "GAP-CLOSE-PWR-3"
			(at -0.0254 -8.255 180)
			(unlocked yes)
			(layer "B.Fab")
			(hide yes)
			(effects
				(font
					(size 1.016 1.016)
					(thickness 0.1524)
				)
				(justify mirror)
			)
		)
		(duplicate_pad_numbers_are_jumpers no)
		(fp_rect
			(start 0.7112 0.4572)
			(end -0.7112 -0.4572)
			(stroke
				(width 0)
				(type default)
			)
			(fill no)
			(layer "B.CrtYd")
		)
		(fp_poly
			(pts
				(xy 0.7112 -0.4572) (xy -0.7112 -0.4572) (xy -0.7112 0.4572) (xy 0.7112 0.4572)
			)
			(stroke
				(width 0)
				(type default)
			)
			(fill no)
			(layer "B.Fab")
		)
		(pad "1" smd rect
			(at 0.3048 0)
			(size 0.6604 0.762)
			(layers "B.Cu" "B.Mask" "B.Paste")
			(net "DUT_VDD")
		)
		(pad "2" smd rect
			(at -0.3048 0)
			(size 0.6604 0.762)
			(layers "B.Cu" "B.Mask" "B.Paste")
			(net "P0V9_E")
		)
	)
	(footprint ""
		(layer "B.Cu")
		(at 252.603 -51.985672 -90)
		(property "Reference" "C550"
			(at 0 0 90)
			(layer "B.SilkS")
			(hide yes)
			(effects
				(font
					(size 1.27 1.27)
				)
				(justify mirror)
			)
		)
		(property "Value" "SCD1U16V1KX-1-GP"
			(at 2.8321 -1.7399 270)
			(unlocked yes)
			(layer "B.Fab")
			(hide yes)
			(effects
				(font
					(size 1.016 1.016)
					(thickness 0.1524)
				)
				(justify mirror)
			)
		)
		(property "Device Type" "C0201H13"
			(at 2.8321 -3.2639 270)
			(unlocked yes)
			(layer "B.Fab")
			(hide yes)
			(effects
				(font
					(size 1.016 1.016)
					(thickness 0.1524)
				)
				(justify mirror)
			)
		)
		(duplicate_pad_numbers_are_jumpers no)
		(fp_rect
			(start 0.2794 0.6477)
			(end -0.2794 -0.6477)
			(stroke
				(width 0)
				(type default)
			)
			(fill no)
			(layer "B.CrtYd")
		)
		(fp_rect
			(start 0.2794 0.6477)
			(end -0.2794 -0.6477)
			(stroke
				(width 0)
				(type default)
			)
			(fill no)
			(layer "B.Fab")
		)
		(pad "1" smd custom
			(at 0 -0.2794 90)
			(size 0.0762 0.0762)
			(layers "B.Cu" "B.Mask" "B.Paste")
			(net "DUT_AVD_PCIE")
			(options
				(clearance outline)
				(anchor circle)
			)
			(primitives
				(gr_poly
					(pts
						(arc
							(start 0.1524 0.127)
							(mid 0.137521 0.162921)
							(end 0.1016 0.1778)
						)
						(arc
							(start -0.1016 0.1778)
							(mid -0.137521 0.162921)
							(end -0.1524 0.127)
						)
						(arc
							(start -0.1524 -0.127)
							(mid -0.137521 -0.162921)
							(end -0.1016 -0.1778)
						)
						(arc
							(start 0.1016 -0.1778)
							(mid 0.137521 -0.162921)
							(end 0.1524 -0.127)
						)
					)
					(width 0)
					(fill yes)
				)
			)
		)
		(pad "2" smd custom
			(at 0 0.2794 90)
			(size 0.0762 0.0762)
			(layers "B.Cu" "B.Mask" "B.Paste")
			(net "GND")
			(options
				(clearance outline)
				(anchor circle)
			)
			(primitives
				(gr_poly
					(pts
						(arc
							(start 0.1524 0.127)
							(mid 0.137521 0.162921)
							(end 0.1016 0.1778)
						)
						(arc
							(start -0.1016 0.1778)
							(mid -0.137521 0.162921)
							(end -0.1524 0.127)
						)
						(arc
							(start -0.1524 -0.127)
							(mid -0.137521 -0.162921)
							(end -0.1016 -0.1778)
						)
						(arc
							(start 0.1016 -0.1778)
							(mid 0.137521 -0.162921)
							(end 0.1524 -0.127)
						)
					)
					(width 0)
					(fill yes)
				)
			)
		)
	)
	(footprint ""
		(layer "B.Cu")
		(at 330.708 -179.07)
		(property "Reference" "R141"
			(at 0 0 0)
			(layer "B.SilkS")
			(hide yes)
			(effects
				(font
					(size 1.27 1.27)
				)
				(justify mirror)
			)
		)
		(property "Value" "4K7R2F-GP"
			(at -0.064008 -3.993896 0)
			(unlocked yes)
			(layer "B.Fab")
			(hide yes)
			(effects
				(font
					(size 1.016 1.016)
					(thickness 0.1524)
				)
				(justify mirror)
			)
		)
		(property "Device Type" "R402H16"
			(at -0.064008 -5.517896 0)
			(unlocked yes)
			(layer "B.Fab")
			(hide yes)
			(effects
				(font
					(size 1.016 1.016)
					(thickness 0.1524)
				)
				(justify mirror)
			)
		)
		(duplicate_pad_numbers_are_jumpers no)
		(fp_line
			(start -0.508 -0.9398)
			(end 0.508 -0.9398)
			(stroke
				(width 0.1524)
				(type default)
			)
			(layer "B.SilkS")
		)
		(fp_line
			(start 0.508 -0.9398)
			(end 0.508 0.9398)
			(stroke
				(width 0.1524)
				(type default)
			)
			(layer "B.SilkS")
		)
		(fp_rect
			(start 0.508 0.9398)
			(end -0.508 -0.9398)
			(stroke
				(width 0)
				(type default)
			)
			(fill no)
			(layer "B.CrtYd")
		)
		(fp_rect
			(start 0.508 0.9398)
			(end -0.508 -0.9398)
			(stroke
				(width 0)
				(type default)
			)
			(fill no)
			(layer "B.Fab")
		)
		(pad "1" smd custom
			(at 0 -0.4445 180)
			(size 0.1397 0.1397)
			(layers "B.Cu" "B.Mask" "B.Paste")
			(net "BMC_SSD_RST#0_A4")
			(options
				(clearance outline)
				(anchor circle)
			)
			(primitives
				(gr_poly
					(pts
						(arc
							(start -0.1778 0.2794)
							(mid -0.249642 0.249642)
							(end -0.2794 0.1778)
						)
						(arc
							(start -0.2794 -0.1778)
							(mid -0.249642 -0.249642)
							(end -0.1778 -0.2794)
						)
						(arc
							(start 0.1778 -0.2794)
							(mid 0.249642 -0.249642)
							(end 0.2794 -0.1778)
						)
						(arc
							(start 0.2794 0.1778)
							(mid 0.249642 0.249642)
							(end 0.1778 0.2794)
						)
					)
					(width 0)
					(fill yes)
				)
			)
		)
		(pad "2" smd custom
			(at 0 0.4445 180)
			(size 0.1397 0.1397)
			(layers "B.Cu" "B.Mask" "B.Paste")
			(net "P3V3_STBY")
			(options
				(clearance outline)
				(anchor circle)
			)
			(primitives
				(gr_poly
					(pts
						(arc
							(start -0.1778 0.2794)
							(mid -0.249642 0.249642)
							(end -0.2794 0.1778)
						)
						(arc
							(start -0.2794 -0.1778)
							(mid -0.249642 -0.249642)
							(end -0.1778 -0.2794)
						)
						(arc
							(start 0.1778 -0.2794)
							(mid 0.249642 -0.249642)
							(end 0.2794 -0.1778)
						)
						(arc
							(start 0.2794 0.1778)
							(mid 0.249642 0.249642)
							(end 0.1778 0.2794)
						)
					)
					(width 0)
					(fill yes)
				)
			)
		)
	)
	(footprint ""
		(layer "B.Cu")
		(at 245.5926 -59.0042 -90)
		(property "Reference" "C506"
			(at 0 0 90)
			(layer "B.SilkS")
			(hide yes)
			(effects
				(font
					(size 1.27 1.27)
				)
				(justify mirror)
			)
		)
		(property "Value" "SCD1U16V1KX-1-GP"
			(at 2.8321 -1.7399 270)
			(unlocked yes)
			(layer "B.Fab")
			(hide yes)
			(effects
				(font
					(size 1.016 1.016)
					(thickness 0.1524)
				)
				(justify mirror)
			)
		)
		(property "Device Type" "C0201H13"
			(at 2.8321 -3.2639 270)
			(unlocked yes)
			(layer "B.Fab")
			(hide yes)
			(effects
				(font
					(size 1.016 1.016)
					(thickness 0.1524)
				)
				(justify mirror)
			)
		)
		(duplicate_pad_numbers_are_jumpers no)
		(fp_rect
			(start 0.2794 0.6477)
			(end -0.2794 -0.6477)
			(stroke
				(width 0)
				(type default)
			)
			(fill no)
			(layer "B.CrtYd")
		)
		(fp_rect
			(start 0.2794 0.6477)
			(end -0.2794 -0.6477)
			(stroke
				(width 0)
				(type default)
			)
			(fill no)
			(layer "B.Fab")
		)
		(pad "1" smd custom
			(at 0 -0.2794 90)
			(size 0.0762 0.0762)
			(layers "B.Cu" "B.Mask" "B.Paste")
			(net "DUT_AVD_TX")
			(options
				(clearance outline)
				(anchor circle)
			)
			(primitives
				(gr_poly
					(pts
						(arc
							(start 0.1524 0.127)
							(mid 0.137521 0.162921)
							(end 0.1016 0.1778)
						)
						(arc
							(start -0.1016 0.1778)
							(mid -0.137521 0.162921)
							(end -0.1524 0.127)
						)
						(arc
							(start -0.1524 -0.127)
							(mid -0.137521 -0.162921)
							(end -0.1016 -0.1778)
						)
						(arc
							(start 0.1016 -0.1778)
							(mid 0.137521 -0.162921)
							(end 0.1524 -0.127)
						)
					)
					(width 0)
					(fill yes)
				)
			)
		)
		(pad "2" smd custom
			(at 0 0.2794 90)
			(size 0.0762 0.0762)
			(layers "B.Cu" "B.Mask" "B.Paste")
			(net "GND")
			(options
				(clearance outline)
				(anchor circle)
			)
			(primitives
				(gr_poly
					(pts
						(arc
							(start 0.1524 0.127)
							(mid 0.137521 0.162921)
							(end 0.1016 0.1778)
						)
						(arc
							(start -0.1016 0.1778)
							(mid -0.137521 0.162921)
							(end -0.1524 0.127)
						)
						(arc
							(start -0.1524 -0.127)
							(mid -0.137521 -0.162921)
							(end -0.1016 -0.1778)
						)
						(arc
							(start 0.1016 -0.1778)
							(mid 0.137521 -0.162921)
							(end 0.1524 -0.127)
						)
					)
					(width 0)
					(fill yes)
				)
			)
		)
	)
	(footprint ""
		(layer "B.Cu")
		(at 235.599986 -38.999922)
		(property "Reference" "TP135"
			(at 0 0 0)
			(layer "B.SilkS")
			(hide yes)
			(effects
				(font
					(size 1.27 1.27)
				)
				(justify mirror)
			)
		)
		(property "Value" "TPAD28-2-GP"
			(at 0.0127 -1.6637 0)
			(unlocked yes)
			(layer "B.Fab")
			(hide yes)
			(effects
				(font
					(size 1.016 1.016)
					(thickness 0.1524)
				)
				(justify mirror)
			)
		)
		(property "Device Type" "TPAD28"
			(at 0.0127 -3.1877 0)
			(unlocked yes)
			(layer "B.Fab")
			(hide yes)
			(effects
				(font
					(size 1.016 1.016)
					(thickness 0.1524)
				)
				(justify mirror)
			)
		)
		(duplicate_pad_numbers_are_jumpers no)
		(fp_poly
			(pts
				(arc
					(start 0.3556 0)
					(mid -0.3556 0)
					(end 0.3556 0)
				)
			)
			(stroke
				(width 0)
				(type default)
			)
			(fill no)
			(layer "B.CrtYd")
		)
		(fp_poly
			(pts
				(arc
					(start 0.6096 0)
					(mid -0.6096 0)
					(end 0.6096 0)
				)
			)
			(stroke
				(width 0)
				(type default)
			)
			(fill no)
			(layer "B.Fab")
		)
		(pad "1" smd circle
			(at 0 0 180)
			(size 0.7112 0.7112)
			(layers "B.Cu" "B.Mask" "B.Paste")
			(net "LBI_ADDR_12_R")
		)
	)
	(footprint ""
		(layer "B.Cu")
		(at 336.677 -184.912 180)
		(property "Reference" "R4154"
			(at 0 0 0)
			(layer "B.SilkS")
			(hide yes)
			(effects
				(font
					(size 1.27 1.27)
				)
				(justify mirror)
			)
		)
		(property "Value" "4K7R2F-GP"
			(at -0.064008 -3.993896 180)
			(unlocked yes)
			(layer "B.Fab")
			(hide yes)
			(effects
				(font
					(size 1.016 1.016)
					(thickness 0.1524)
				)
				(justify mirror)
			)
		)
		(property "Device Type" "R402H16"
			(at -0.064008 -5.517896 180)
			(unlocked yes)
			(layer "B.Fab")
			(hide yes)
			(effects
				(font
					(size 1.016 1.016)
					(thickness 0.1524)
				)
				(justify mirror)
			)
		)
		(duplicate_pad_numbers_are_jumpers no)
		(fp_line
			(start 0.508 -0.9398)
			(end 0.508 0.9398)
			(stroke
				(width 0.1524)
				(type default)
			)
			(layer "B.SilkS")
		)
		(fp_line
			(start -0.508 -0.9398)
			(end 0.508 -0.9398)
			(stroke
				(width 0.1524)
				(type default)
			)
			(layer "B.SilkS")
		)
		(fp_rect
			(start 0.508 0.9398)
			(end -0.508 -0.9398)
			(stroke
				(width 0)
				(type default)
			)
			(fill no)
			(layer "B.CrtYd")
		)
		(fp_rect
			(start 0.508 0.9398)
			(end -0.508 -0.9398)
			(stroke
				(width 0)
				(type default)
			)
			(fill no)
			(layer "B.Fab")
		)
		(pad "1" smd custom
			(at 0 -0.4445)
			(size 0.1397 0.1397)
			(layers "B.Cu" "B.Mask" "B.Paste")
			(net "SSD_PERST#14")
			(options
				(clearance outline)
				(anchor circle)
			)
			(primitives
				(gr_poly
					(pts
						(arc
							(start -0.1778 0.2794)
							(mid -0.249642 0.249642)
							(end -0.2794 0.1778)
						)
						(arc
							(start -0.2794 -0.1778)
							(mid -0.249642 -0.249642)
							(end -0.1778 -0.2794)
						)
						(arc
							(start 0.1778 -0.2794)
							(mid 0.249642 -0.249642)
							(end 0.2794 -0.1778)
						)
						(arc
							(start 0.2794 0.1778)
							(mid 0.249642 0.249642)
							(end 0.1778 0.2794)
						)
					)
					(width 0)
					(fill yes)
				)
			)
		)
		(pad "2" smd custom
			(at 0 0.4445)
			(size 0.1397 0.1397)
			(layers "B.Cu" "B.Mask" "B.Paste")
			(net "P3V3_STBY")
			(options
				(clearance outline)
				(anchor circle)
			)
			(primitives
				(gr_poly
					(pts
						(arc
							(start -0.1778 0.2794)
							(mid -0.249642 0.249642)
							(end -0.2794 0.1778)
						)
						(arc
							(start -0.2794 -0.1778)
							(mid -0.249642 -0.249642)
							(end -0.1778 -0.2794)
						)
						(arc
							(start 0.1778 -0.2794)
							(mid 0.249642 -0.249642)
							(end 0.2794 -0.1778)
						)
						(arc
							(start 0.2794 0.1778)
							(mid 0.249642 0.249642)
							(end 0.1778 0.2794)
						)
					)
					(width 0)
					(fill yes)
				)
			)
		)
	)
)
